(kicad_pcb
	(version 20260206)
	(generator "pcbnew")
	(generator_version "10.0")
	(general
		(thickness 1.6)
		(legacy_teardrops no)
	)
	(paper "A4")
	(title_block
		(title "01162023_DA0F0TEBIF0_F0T_Expander_BD_F_brd_V02_OCP.brd")
		(comment 1 "Grand Teton / footprints 9337-9345 of 9728")
	)
	(layers
		(0 "F.Cu" signal "TOP")
		(4 "In1.Cu" signal "GND")
		(6 "In2.Cu" signal "VCC")
		(8 "In3.Cu" signal "VCC1")
		(10 "In4.Cu" signal "GND1")
		(12 "In5.Cu" signal "IN1")
		(14 "In6.Cu" signal "GND2")
		(16 "In7.Cu" signal "IN2")
		(18 "In8.Cu" signal "GND3")
		(20 "In9.Cu" signal "IN3")
		(22 "In10.Cu" signal "GND4")
		(24 "In11.Cu" signal "IN4")
		(26 "In12.Cu" signal "GND5")
		(28 "In13.Cu" signal "IN5")
		(30 "In14.Cu" signal "GND6")
		(32 "In15.Cu" signal "IN6")
		(34 "In16.Cu" signal "GND7")
		(2 "B.Cu" signal "BOTTOM")
		(9 "F.Adhes" user "F.Adhesive")
		(11 "B.Adhes" user "B.Adhesive")
		(13 "F.Paste" user "Package Geometry/Pastemask Top")
		(15 "B.Paste" user "Package Geometry/Pastemask Bottom")
		(5 "F.SilkS" user "Ref Des/Silkscreen Top")
		(7 "B.SilkS" user "Ref Des/Silkscreen Bottom")
		(1 "F.Mask" user "Board Geometry/Soldermask Top")
		(3 "B.Mask" user "Board Geometry/Soldermask Bottom")
		(17 "Dwgs.User" user "User.Drawings")
		(19 "Cmts.User" user "User.Comments")
		(21 "Eco1.User" user "User.Eco1")
		(23 "Eco2.User" user "User.Eco2")
		(25 "Edge.Cuts" user "Board Geometry/Outline")
		(27 "Margin" user)
		(31 "F.CrtYd" user "Package Geometry/Place Bound Top")
		(29 "B.CrtYd" user "Package Geometry/Place Bound Bottom")
		(35 "F.Fab" user "Ref Des/Assembly Top")
		(33 "B.Fab" user "Ref Des/Assembly Bottom")
	)
	(footprint ""
		(layer "B.Cu")
		(at 212.09 -201.549 -90)
		(property "Reference" "R1520"
			(at 0 0 90)
			(layer "B.SilkS")
			(hide yes)
			(effects
				(font
					(size 1.27 1.27)
				)
				(justify mirror)
			)
		)
		(property "Value" ""
			(at 0 0 90)
			(layer "B.Fab")
			(effects
				(font
					(size 1.27 1.27)
				)
				(justify mirror)
			)
		)
		(duplicate_pad_numbers_are_jumpers no)
		(fp_line
			(start -0.7874 0.4064)
			(end 0.7874 0.4064)
			(stroke
				(width 0.1524)
				(type default)
			)
			(layer "B.SilkS")
		)
		(fp_line
			(start 0.7874 0.4064)
			(end 0.7874 -0.4064)
			(stroke
				(width 0.1524)
				(type default)
			)
			(layer "B.SilkS")
		)
		(fp_line
			(start -0.7874 -0.4064)
			(end -0.7874 0.4064)
			(stroke
				(width 0.1524)
				(type default)
			)
			(layer "B.SilkS")
		)
		(fp_line
			(start 0.7874 -0.4064)
			(end -0.7874 -0.4064)
			(stroke
				(width 0.1524)
				(type default)
			)
			(layer "B.SilkS")
		)
		(fp_line
			(start -0.67945 0.3048)
			(end -0.120396 0.3048)
			(stroke
				(width 0.1)
				(type default)
			)
			(layer "B.Fab")
		)
		(fp_line
			(start -0.120396 0.3048)
			(end -0.120396 0.2794)
			(stroke
				(width 0.1)
				(type default)
			)
			(layer "B.Fab")
		)
		(fp_line
			(start 0.12065 0.3048)
			(end 0.67945 0.3048)
			(stroke
				(width 0.1)
				(type default)
			)
			(layer "B.Fab")
		)
		(fp_line
			(start 0.67945 0.3048)
			(end 0.67945 -0.305054)
			(stroke
				(width 0.1)
				(type default)
			)
			(layer "B.Fab")
		)
		(fp_line
			(start -0.120396 0.2794)
			(end 0.12065 0.2794)
			(stroke
				(width 0.1)
				(type default)
			)
			(layer "B.Fab")
		)
		(fp_line
			(start 0.12065 0.2794)
			(end 0.12065 0.3048)
			(stroke
				(width 0.1)
				(type default)
			)
			(layer "B.Fab")
		)
		(fp_line
			(start -0.12065 -0.2794)
			(end -0.12065 -0.3048)
			(stroke
				(width 0.1)
				(type default)
			)
			(layer "B.Fab")
		)
		(fp_line
			(start 0.12065 -0.2794)
			(end -0.12065 -0.2794)
			(stroke
				(width 0.1)
				(type default)
			)
			(layer "B.Fab")
		)
		(fp_line
			(start -0.67945 -0.3048)
			(end -0.67945 0.3048)
			(stroke
				(width 0.1)
				(type default)
			)
			(layer "B.Fab")
		)
		(fp_line
			(start -0.12065 -0.3048)
			(end -0.67945 -0.3048)
			(stroke
				(width 0.1)
				(type default)
			)
			(layer "B.Fab")
		)
		(fp_line
			(start 0.12065 -0.305054)
			(end 0.12065 -0.2794)
			(stroke
				(width 0.1)
				(type default)
			)
			(layer "B.Fab")
		)
		(fp_line
			(start 0.67945 -0.305054)
			(end 0.12065 -0.305054)
			(stroke
				(width 0.1)
				(type default)
			)
			(layer "B.Fab")
		)
		(pad "1" smd circle
			(at 0.40005 0 90)
			(size 0 0)
			(layers "B.Cu" "B.Mask" "B.Paste")
			(net "SMB_NIC5_LS_R_SCL")
		)
		(pad "2" smd circle
			(at -0.40005 0 90)
			(size 0 0)
			(layers "B.Cu" "B.Mask" "B.Paste")
			(net "SMB_NIC5_R_SCL")
		)
	)
	(footprint ""
		(layer "B.Cu")
		(at 25.117298 -260.131306)
		(property "Reference" "C3071"
			(at 0 0 0)
			(layer "B.SilkS")
			(hide yes)
			(effects
				(font
					(size 1.27 1.27)
				)
				(justify mirror)
			)
		)
		(property "Value" ""
			(at 0 0 0)
			(layer "B.Fab")
			(effects
				(font
					(size 1.27 1.27)
				)
				(justify mirror)
			)
		)
		(duplicate_pad_numbers_are_jumpers no)
		(fp_line
			(start -0.299974 -0.150114)
			(end -0.299974 0.150114)
			(stroke
				(width 0.1)
				(type default)
			)
			(layer "B.Fab")
		)
		(fp_line
			(start -0.299974 0.150114)
			(end 0.299974 0.150114)
			(stroke
				(width 0.1)
				(type default)
			)
			(layer "B.Fab")
		)
		(fp_line
			(start 0.299974 -0.150114)
			(end -0.299974 -0.150114)
			(stroke
				(width 0.1)
				(type default)
			)
			(layer "B.Fab")
		)
		(fp_line
			(start 0.299974 0.150114)
			(end 0.299974 -0.150114)
			(stroke
				(width 0.1)
				(type default)
			)
			(layer "B.Fab")
		)
		(pad "1" smd rect
			(at 0.2667 0 180)
			(size 0.3048 0.381)
			(layers "B.Cu" "B.Mask" "B.Paste")
			(net "P1V8_VDDA_PEX0")
		)
		(pad "2" smd rect
			(at -0.2667 0 180)
			(size 0.3048 0.381)
			(layers "B.Cu" "B.Mask" "B.Paste")
			(net "GND")
		)
	)
	(footprint ""
		(layer "B.Cu")
		(at 63.001398 -305.399948 -90)
		(property "Reference" "C2966"
			(at 0 0 90)
			(layer "B.SilkS")
			(hide yes)
			(effects
				(font
					(size 1.27 1.27)
				)
				(justify mirror)
			)
		)
		(property "Value" ""
			(at 0 0 90)
			(layer "B.Fab")
			(effects
				(font
					(size 1.27 1.27)
				)
				(justify mirror)
			)
		)
		(duplicate_pad_numbers_are_jumpers no)
		(fp_line
			(start -0.299974 0.150114)
			(end 0.299974 0.150114)
			(stroke
				(width 0.1)
				(type default)
			)
			(layer "B.Fab")
		)
		(fp_line
			(start 0.299974 0.150114)
			(end 0.299974 -0.150114)
			(stroke
				(width 0.1)
				(type default)
			)
			(layer "B.Fab")
		)
		(fp_line
			(start -0.299974 -0.150114)
			(end -0.299974 0.150114)
			(stroke
				(width 0.1)
				(type default)
			)
			(layer "B.Fab")
		)
		(fp_line
			(start 0.299974 -0.150114)
			(end -0.299974 -0.150114)
			(stroke
				(width 0.1)
				(type default)
			)
			(layer "B.Fab")
		)
		(pad "1" smd rect
			(at 0.2667 0 90)
			(size 0.3048 0.381)
			(layers "B.Cu" "B.Mask" "B.Paste")
			(net "P1V25_SERDES_VDDPLL_PEX0")
		)
		(pad "2" smd rect
			(at -0.2667 0 90)
			(size 0.3048 0.381)
			(layers "B.Cu" "B.Mask" "B.Paste")
			(net "GND")
		)
	)
	(footprint ""
		(layer "B.Cu")
		(at 214.472774 -234.205526 -90)
		(property "Reference" "R6334"
			(at 0 0 90)
			(layer "B.SilkS")
			(hide yes)
			(effects
				(font
					(size 1.27 1.27)
				)
				(justify mirror)
			)
		)
		(property "Value" ""
			(at 0 0 90)
			(layer "B.Fab")
			(effects
				(font
					(size 1.27 1.27)
				)
				(justify mirror)
			)
		)
		(duplicate_pad_numbers_are_jumpers no)
		(fp_line
			(start -0.7874 0.4064)
			(end 0.7874 0.4064)
			(stroke
				(width 0.1524)
				(type default)
			)
			(layer "B.SilkS")
		)
		(fp_line
			(start 0.7874 0.4064)
			(end 0.7874 -0.4064)
			(stroke
				(width 0.1524)
				(type default)
			)
			(layer "B.SilkS")
		)
		(fp_line
			(start -0.7874 -0.4064)
			(end -0.7874 0.4064)
			(stroke
				(width 0.1524)
				(type default)
			)
			(layer "B.SilkS")
		)
		(fp_line
			(start 0.7874 -0.4064)
			(end -0.7874 -0.4064)
			(stroke
				(width 0.1524)
				(type default)
			)
			(layer "B.SilkS")
		)
		(fp_line
			(start -0.67945 0.3048)
			(end -0.120396 0.3048)
			(stroke
				(width 0.1)
				(type default)
			)
			(layer "B.Fab")
		)
		(fp_line
			(start -0.120396 0.3048)
			(end -0.120396 0.2794)
			(stroke
				(width 0.1)
				(type default)
			)
			(layer "B.Fab")
		)
		(fp_line
			(start 0.12065 0.3048)
			(end 0.67945 0.3048)
			(stroke
				(width 0.1)
				(type default)
			)
			(layer "B.Fab")
		)
		(fp_line
			(start 0.67945 0.3048)
			(end 0.67945 -0.305054)
			(stroke
				(width 0.1)
				(type default)
			)
			(layer "B.Fab")
		)
		(fp_line
			(start -0.120396 0.2794)
			(end 0.12065 0.2794)
			(stroke
				(width 0.1)
				(type default)
			)
			(layer "B.Fab")
		)
		(fp_line
			(start 0.12065 0.2794)
			(end 0.12065 0.3048)
			(stroke
				(width 0.1)
				(type default)
			)
			(layer "B.Fab")
		)
		(fp_line
			(start -0.12065 -0.2794)
			(end -0.12065 -0.3048)
			(stroke
				(width 0.1)
				(type default)
			)
			(layer "B.Fab")
		)
		(fp_line
			(start 0.12065 -0.2794)
			(end -0.12065 -0.2794)
			(stroke
				(width 0.1)
				(type default)
			)
			(layer "B.Fab")
		)
		(fp_line
			(start -0.67945 -0.3048)
			(end -0.67945 0.3048)
			(stroke
				(width 0.1)
				(type default)
			)
			(layer "B.Fab")
		)
		(fp_line
			(start -0.12065 -0.3048)
			(end -0.67945 -0.3048)
			(stroke
				(width 0.1)
				(type default)
			)
			(layer "B.Fab")
		)
		(fp_line
			(start 0.12065 -0.305054)
			(end 0.12065 -0.2794)
			(stroke
				(width 0.1)
				(type default)
			)
			(layer "B.Fab")
		)
		(fp_line
			(start 0.67945 -0.305054)
			(end 0.12065 -0.305054)
			(stroke
				(width 0.1)
				(type default)
			)
			(layer "B.Fab")
		)
		(pad "1" smd circle
			(at 0.40005 0 90)
			(size 0 0)
			(layers "B.Cu" "B.Mask" "B.Paste")
			(net "SMB_PEX3_SCL")
		)
		(pad "2" smd circle
			(at -0.40005 0 90)
			(size 0 0)
			(layers "B.Cu" "B.Mask" "B.Paste")
			(net "SMB_PEX3_MUX_SCL")
		)
	)
	(footprint ""
		(layer "B.Cu")
		(at 223.90735 -456.90663 180)
		(property "Reference" "X79"
			(at 0.1778 -1.92913 180)
			(unlocked yes)
			(layer "B.SilkS")
			(effects
				(font
					(size 0.7874 0.5842)
					(thickness 0.1524)
				)
				(justify left mirror)
			)
		)
		(property "Value" ""
			(at 0 0 0)
			(layer "B.Fab")
			(effects
				(font
					(size 1.27 1.27)
				)
				(justify mirror)
			)
		)
		(property "Device Type" "TP_TDR_4P_FTS_MPKT4_H025P0200_IO_TP15_TP_TDR_4P_DIP"
			(at -1.30175 1.27 90)
			(unlocked yes)
			(layer "B.Fab")
			(hide yes)
			(effects
				(font
					(size 0.635 0.4064)
					(thickness 0.1524)
				)
				(justify mirror)
			)
		)
		(property "User Part Number" "TP15"
			(at -1.30175 1.27 90)
			(unlocked yes)
			(layer "Cmts.User")
			(hide yes)
			(effects
				(font
					(size 0.635 0.4064)
					(thickness 0.1524)
				)
				(justify mirror)
			)
		)
		(duplicate_pad_numbers_are_jumpers no)
		(fp_line
			(start 0 3.81)
			(end -2.54 3.81)
			(stroke
				(width 0.1524)
				(type default)
			)
			(layer "B.SilkS")
		)
		(fp_line
			(start 0 3.175)
			(end 0 3.81)
			(stroke
				(width 0.1524)
				(type default)
			)
			(layer "B.SilkS")
		)
		(fp_line
			(start 0 0.635)
			(end 0 1.905)
			(stroke
				(width 0.1524)
				(type default)
			)
			(layer "B.SilkS")
		)
		(fp_line
			(start 0 -1.27)
			(end 0 -0.635)
			(stroke
				(width 0.1524)
				(type default)
			)
			(layer "B.SilkS")
		)
		(fp_line
			(start -2.54 3.81)
			(end -2.54 3.6703)
			(stroke
				(width 0.1524)
				(type default)
			)
			(layer "B.SilkS")
		)
		(fp_line
			(start -2.54 1.4097)
			(end -2.54 1.1303)
			(stroke
				(width 0.1524)
				(type default)
			)
			(layer "B.SilkS")
		)
		(fp_line
			(start -2.54 -1.1303)
			(end -2.54 -1.27)
			(stroke
				(width 0.1524)
				(type default)
			)
			(layer "B.SilkS")
		)
		(fp_line
			(start -2.54 -1.27)
			(end 0 -1.27)
			(stroke
				(width 0.1524)
				(type default)
			)
			(layer "B.SilkS")
		)
		(fp_poly
			(pts
				(xy 0.761746 0) (xy 2.285746 -0.762) (xy 2.285746 0.762)
			)
			(stroke
				(width 0)
				(type default)
			)
			(fill yes)
			(layer "B.SilkS")
		)
		(fp_line
			(start 0 3.81)
			(end -2.54 3.81)
			(stroke
				(width 0.1)
				(type default)
			)
			(layer "B.Fab")
		)
		(fp_line
			(start 0 -1.27)
			(end 0 3.81)
			(stroke
				(width 0.1)
				(type default)
			)
			(layer "B.Fab")
		)
		(fp_line
			(start -2.54 3.81)
			(end -2.54 -1.27)
			(stroke
				(width 0.1)
				(type default)
			)
			(layer "B.Fab")
		)
		(fp_line
			(start -2.54 -1.27)
			(end 0 -1.27)
			(stroke
				(width 0.1)
				(type default)
			)
			(layer "B.Fab")
		)
		(fp_poly
			(pts
				(xy 0.761746 0) (xy 2.285746 -0.762) (xy 2.285746 0.762)
			)
			(stroke
				(width 0)
				(type default)
			)
			(fill yes)
			(layer "B.Fab")
		)
		(pad "1" thru_hole circle
			(at 0 0)
			(size 1.0033 1.0033)
			(drill 0.249936)
			(layers "*.Cu" "*.Mask")
			(remove_unused_layers no)
			(net "TDR_DIFF_100_IN6_DIN")
			(clearance 0.10795)
			(padstack
				(mode front_inner_back)
				(layer "Inner"
					(shape circle)
					(size 0.8001 0.8001)
					(clearance 0.1524)
				)
				(layer "B.Cu"
					(shape circle)
					(size 1.0033 1.0033)
					(thermal_gap 0.10795)
					(clearance 0.10795)
				)
			)
		)
		(pad "2" thru_hole circle
			(at -2.54 0)
			(size 1.9939 1.9939)
			(drill 0.249936)
			(layers "*.Cu" "*.Mask")
			(remove_unused_layers no)
			(net "COUPON_GND1")
			(clearance 0.10795)
			(padstack
				(mode front_inner_back)
				(layer "Inner"
					(shape circle)
					(size 0.8001 0.8001)
					(clearance 0.1524)
				)
				(layer "B.Cu"
					(shape circle)
					(size 1.9939 1.9939)
					(thermal_gap 0.10795)
					(clearance 0.10795)
				)
			)
		)
		(pad "3" thru_hole circle
			(at -2.54 2.54)
			(size 1.9939 1.9939)
			(drill 0.249936)
			(layers "*.Cu" "*.Mask")
			(remove_unused_layers no)
			(net "COUPON_GND1")
			(clearance 0.10795)
			(padstack
				(mode front_inner_back)
				(layer "Inner"
					(shape circle)
					(size 0.8001 0.8001)
					(clearance 0.1524)
				)
				(layer "B.Cu"
					(shape circle)
					(size 1.9939 1.9939)
					(thermal_gap 0.10795)
					(clearance 0.10795)
				)
			)
		)
		(pad "4" thru_hole circle
			(at 0 2.54)
			(size 1.0033 1.0033)
			(drill 0.249936)
			(layers "*.Cu" "*.Mask")
			(remove_unused_layers no)
			(net "TDR_DIFF_100_IN6_DIP")
			(clearance 0.10795)
			(padstack
				(mode front_inner_back)
				(layer "Inner"
					(shape circle)
					(size 0.8001 0.8001)
					(clearance 0.1524)
				)
				(layer "B.Cu"
					(shape circle)
					(size 1.0033 1.0033)
					(thermal_gap 0.10795)
					(clearance 0.10795)
				)
			)
		)
	)
	(footprint ""
		(layer "B.Cu")
		(at 100.868734 -237.306612 -90)
		(property "Reference" "PC1005"
			(at 0 0 90)
			(layer "B.SilkS")
			(hide yes)
			(effects
				(font
					(size 1.27 1.27)
				)
				(justify mirror)
			)
		)
		(property "Value" ""
			(at 0 0 90)
			(layer "B.Fab")
			(effects
				(font
					(size 1.27 1.27)
				)
				(justify mirror)
			)
		)
		(duplicate_pad_numbers_are_jumpers no)
		(fp_line
			(start -1.524 0.762)
			(end 1.524 0.762)
			(stroke
				(width 0.1524)
				(type default)
			)
			(layer "B.SilkS")
		)
		(fp_line
			(start 1.524 0.762)
			(end 1.524 -0.762)
			(stroke
				(width 0.1524)
				(type default)
			)
			(layer "B.SilkS")
		)
		(fp_line
			(start -1.524 -0.762)
			(end -1.524 0.762)
			(stroke
				(width 0.1524)
				(type default)
			)
			(layer "B.SilkS")
		)
		(fp_line
			(start 1.524 -0.762)
			(end -1.524 -0.762)
			(stroke
				(width 0.1524)
				(type default)
			)
			(layer "B.SilkS")
		)
		(fp_line
			(start -1.1049 0.724916)
			(end -1.1049 -0.724916)
			(stroke
				(width 0.1)
				(type default)
			)
			(layer "B.Fab")
		)
		(fp_line
			(start 1.1049 0.724916)
			(end -1.1049 0.724916)
			(stroke
				(width 0.1)
				(type default)
			)
			(layer "B.Fab")
		)
		(fp_line
			(start -1.1049 -0.724916)
			(end 1.1049 -0.724916)
			(stroke
				(width 0.1)
				(type default)
			)
			(layer "B.Fab")
		)
		(fp_line
			(start 1.1049 -0.724916)
			(end 1.1049 0.724916)
			(stroke
				(width 0.1)
				(type default)
			)
			(layer "B.Fab")
		)
		(pad "1" smd rect
			(at 0.889 0 270)
			(size 1.016 1.27)
			(layers "B.Cu" "B.Mask" "B.Paste")
			(net "P1V8_PEX_R")
		)
		(pad "2" smd rect
			(at -0.889 0 270)
			(size 1.016 1.27)
			(layers "B.Cu" "B.Mask" "B.Paste")
			(net "GND")
		)
	)
	(footprint ""
		(layer "B.Cu")
		(at 178.124866 -293.99992 -90)
		(property "Reference" "C1397"
			(at 0 0 90)
			(layer "B.SilkS")
			(hide yes)
			(effects
				(font
					(size 1.27 1.27)
				)
				(justify mirror)
			)
		)
		(property "Value" ""
			(at 0 0 90)
			(layer "B.Fab")
			(effects
				(font
					(size 1.27 1.27)
				)
				(justify mirror)
			)
		)
		(duplicate_pad_numbers_are_jumpers no)
		(fp_line
			(start -0.299974 0.150114)
			(end 0.299974 0.150114)
			(stroke
				(width 0.1)
				(type default)
			)
			(layer "B.Fab")
		)
		(fp_line
			(start 0.299974 0.150114)
			(end 0.299974 -0.150114)
			(stroke
				(width 0.1)
				(type default)
			)
			(layer "B.Fab")
		)
		(fp_line
			(start -0.299974 -0.150114)
			(end -0.299974 0.150114)
			(stroke
				(width 0.1)
				(type default)
			)
			(layer "B.Fab")
		)
		(fp_line
			(start 0.299974 -0.150114)
			(end -0.299974 -0.150114)
			(stroke
				(width 0.1)
				(type default)
			)
			(layer "B.Fab")
		)
		(pad "1" smd rect
			(at 0.2667 0 90)
			(size 0.3048 0.381)
			(layers "B.Cu" "B.Mask" "B.Paste")
			(net "P0V8_PEX1")
		)
		(pad "2" smd rect
			(at -0.2667 0 90)
			(size 0.3048 0.381)
			(layers "B.Cu" "B.Mask" "B.Paste")
			(net "GND")
		)
	)
	(footprint ""
		(layer "B.Cu")
		(at 305.6001 -109.251496)
		(property "Reference" "C924"
			(at 0 0 0)
			(layer "B.SilkS")
			(hide yes)
			(effects
				(font
					(size 1.27 1.27)
				)
				(justify mirror)
			)
		)
		(property "Value" ""
			(at 0 0 0)
			(layer "B.Fab")
			(effects
				(font
					(size 1.27 1.27)
				)
				(justify mirror)
			)
		)
		(duplicate_pad_numbers_are_jumpers no)
		(fp_line
			(start -0.299974 -0.150114)
			(end -0.299974 0.150114)
			(stroke
				(width 0.1)
				(type default)
			)
			(layer "B.Fab")
		)
		(fp_line
			(start -0.299974 0.150114)
			(end 0.299974 0.150114)
			(stroke
				(width 0.1)
				(type default)
			)
			(layer "B.Fab")
		)
		(fp_line
			(start 0.299974 -0.150114)
			(end -0.299974 -0.150114)
			(stroke
				(width 0.1)
				(type default)
			)
			(layer "B.Fab")
		)
		(fp_line
			(start 0.299974 0.150114)
			(end 0.299974 -0.150114)
			(stroke
				(width 0.1)
				(type default)
			)
			(layer "B.Fab")
		)
		(pad "1" smd rect
			(at 0.2667 0 180)
			(size 0.3048 0.381)
			(layers "B.Cu" "B.Mask" "B.Paste")
			(net "P12V_NIC5")
		)
		(pad "2" smd rect
			(at -0.2667 0 180)
			(size 0.3048 0.381)
			(layers "B.Cu" "B.Mask" "B.Paste")
			(net "GND")
		)
	)
	(footprint ""
		(layer "B.Cu")
		(at 58.699908 -299.699934 -90)
		(property "Reference" "C1189"
			(at 0 0 90)
			(layer "B.SilkS")
			(hide yes)
			(effects
				(font
					(size 1.27 1.27)
				)
				(justify mirror)
			)
		)
		(property "Value" ""
			(at 0 0 90)
			(layer "B.Fab")
			(effects
				(font
					(size 1.27 1.27)
				)
				(justify mirror)
			)
		)
		(duplicate_pad_numbers_are_jumpers no)
		(fp_line
			(start -0.299974 0.150114)
			(end 0.299974 0.150114)
			(stroke
				(width 0.1)
				(type default)
			)
			(layer "B.Fab")
		)
		(fp_line
			(start 0.299974 0.150114)
			(end 0.299974 -0.150114)
			(stroke
				(width 0.1)
				(type default)
			)
			(layer "B.Fab")
		)
		(fp_line
			(start -0.299974 -0.150114)
			(end -0.299974 0.150114)
			(stroke
				(width 0.1)
				(type default)
			)
			(layer "B.Fab")
		)
		(fp_line
			(start 0.299974 -0.150114)
			(end -0.299974 -0.150114)
			(stroke
				(width 0.1)
				(type default)
			)
			(layer "B.Fab")
		)
		(pad "1" smd rect
			(at 0.2667 0 90)
			(size 0.3048 0.381)
			(layers "B.Cu" "B.Mask" "B.Paste")
			(net "P0V8_SERDES_VDDA_PEX0")
		)
		(pad "2" smd rect
			(at -0.2667 0 90)
			(size 0.3048 0.381)
			(layers "B.Cu" "B.Mask" "B.Paste")
			(net "GND")
		)
	)
)
